(kicad_pcb
	(version 20260206)
	(generator "pcbnew")
	(generator_version "10.0")
	(general
		(thickness 1.6)
		(legacy_teardrops no)
	)
	(paper "A4")
	(title_block
		(title "03242023_DA0F0TMBIJ0_F0T_Motherboard_J_brd_V01_OCP.brd")
		(comment 1 "Grand Teton / footprints 599-603 of 6105")
	)
	(layers
		(0 "F.Cu" signal "TOP")
		(4 "In1.Cu" signal "GND")
		(6 "In2.Cu" signal "IN1")
		(8 "In3.Cu" signal "GND1")
		(10 "In4.Cu" signal "IN2")
		(12 "In5.Cu" signal "GND2")
		(14 "In6.Cu" signal "IN3")
		(16 "In7.Cu" signal "GND3")
		(18 "In8.Cu" signal "VCC")
		(20 "In9.Cu" signal "VCC1")
		(22 "In10.Cu" signal "GND4")
		(24 "In11.Cu" signal "IN4")
		(26 "In12.Cu" signal "GND5")
		(28 "In13.Cu" signal "IN5")
		(30 "In14.Cu" signal "GND6")
		(32 "In15.Cu" signal "IN6")
		(34 "In16.Cu" signal "GND7")
		(2 "B.Cu" signal "BOTTOM")
		(9 "F.Adhes" user "F.Adhesive")
		(11 "B.Adhes" user "B.Adhesive")
		(13 "F.Paste" user "Package Geometry/Pastemask Top")
		(15 "B.Paste" user "Package Geometry/Pastemask Bottom")
		(5 "F.SilkS" user "Ref Des/Silkscreen Top")
		(7 "B.SilkS" user "Ref Des/Silkscreen Bottom")
		(1 "F.Mask" user "Board Geometry/Soldermask Top")
		(3 "B.Mask" user "Board Geometry/Soldermask Bottom")
		(17 "Dwgs.User" user "User.Drawings")
		(19 "Cmts.User" user "User.Comments")
		(21 "Eco1.User" user "User.Eco1")
		(23 "Eco2.User" user "User.Eco2")
		(25 "Edge.Cuts" user "Board Geometry/Outline")
		(27 "Margin" user)
		(31 "F.CrtYd" user "Package Geometry/Place Bound Top")
		(29 "B.CrtYd" user "Package Geometry/Place Bound Bottom")
		(35 "F.Fab" user "Ref Des/Assembly Top")
		(33 "B.Fab" user "Ref Des/Assembly Bottom")
	)
	(footprint ""
		(layer "F.Cu")
		(at 243.045488 -136.348724)
		(property "Reference" "R4715"
			(at 0 0 0)
			(layer "F.SilkS")
			(hide yes)
			(effects
				(font
					(size 1.27 1.27)
				)
			)
		)
		(property "Value" ""
			(at 0 0 0)
			(layer "F.Fab")
			(effects
				(font
					(size 1.27 1.27)
				)
			)
		)
		(duplicate_pad_numbers_are_jumpers no)
		(fp_line
			(start -0.7874 -0.4064)
			(end 0.7874 -0.4064)
			(stroke
				(width 0.1524)
				(type default)
			)
			(layer "F.SilkS")
		)
		(fp_line
			(start -0.7874 0.4064)
			(end -0.7874 -0.4064)
			(stroke
				(width 0.1524)
				(type default)
			)
			(layer "F.SilkS")
		)
		(fp_line
			(start 0.7874 -0.4064)
			(end 0.7874 0.4064)
			(stroke
				(width 0.1524)
				(type default)
			)
			(layer "F.SilkS")
		)
		(fp_line
			(start 0.7874 0.4064)
			(end -0.7874 0.4064)
			(stroke
				(width 0.1524)
				(type default)
			)
			(layer "F.SilkS")
		)
		(fp_line
			(start -0.67945 -0.305054)
			(end -0.12065 -0.305054)
			(stroke
				(width 0.1)
				(type default)
			)
			(layer "F.Fab")
		)
		(fp_line
			(start -0.67945 0.3048)
			(end -0.67945 -0.305054)
			(stroke
				(width 0.1)
				(type default)
			)
			(layer "F.Fab")
		)
		(fp_line
			(start -0.12065 -0.305054)
			(end -0.12065 -0.2794)
			(stroke
				(width 0.1)
				(type default)
			)
			(layer "F.Fab")
		)
		(fp_line
			(start -0.12065 -0.2794)
			(end 0.12065 -0.2794)
			(stroke
				(width 0.1)
				(type default)
			)
			(layer "F.Fab")
		)
		(fp_line
			(start -0.12065 0.2794)
			(end -0.12065 0.3048)
			(stroke
				(width 0.1)
				(type default)
			)
			(layer "F.Fab")
		)
		(fp_line
			(start -0.12065 0.3048)
			(end -0.67945 0.3048)
			(stroke
				(width 0.1)
				(type default)
			)
			(layer "F.Fab")
		)
		(fp_line
			(start 0.120396 0.2794)
			(end -0.12065 0.2794)
			(stroke
				(width 0.1)
				(type default)
			)
			(layer "F.Fab")
		)
		(fp_line
			(start 0.120396 0.3048)
			(end 0.120396 0.2794)
			(stroke
				(width 0.1)
				(type default)
			)
			(layer "F.Fab")
		)
		(fp_line
			(start 0.12065 -0.3048)
			(end 0.67945 -0.3048)
			(stroke
				(width 0.1)
				(type default)
			)
			(layer "F.Fab")
		)
		(fp_line
			(start 0.12065 -0.2794)
			(end 0.12065 -0.3048)
			(stroke
				(width 0.1)
				(type default)
			)
			(layer "F.Fab")
		)
		(fp_line
			(start 0.67945 -0.3048)
			(end 0.67945 0.3048)
			(stroke
				(width 0.1)
				(type default)
			)
			(layer "F.Fab")
		)
		(fp_line
			(start 0.67945 0.3048)
			(end 0.120396 0.3048)
			(stroke
				(width 0.1)
				(type default)
			)
			(layer "F.Fab")
		)
		(pad "1" smd circle
			(at -0.40005 0)
			(size 0 0)
			(layers "F.Cu" "F.Mask" "F.Paste")
			(net "SMB_HOST_3V3AUX_SCL_R4")
		)
		(pad "2" smd circle
			(at 0.40005 0)
			(size 0 0)
			(layers "F.Cu" "F.Mask" "F.Paste")
			(net "SMB_HOST_3V3AUX_PLD_SCL")
		)
	)
	(footprint ""
		(layer "F.Cu")
		(at 311.970674 -14.69136 180)
		(property "Reference" "U157"
			(at 1.306068 2.358644 0)
			(unlocked yes)
			(layer "F.SilkS")
			(effects
				(font
					(size 0.7874 0.5842)
					(thickness 0.1524)
				)
				(justify left)
			)
		)
		(property "Value" ""
			(at 0 0 180)
			(layer "F.Fab")
			(effects
				(font
					(size 1.27 1.27)
				)
			)
		)
		(duplicate_pad_numbers_are_jumpers no)
		(fp_line
			(start 1.733296 1.549908)
			(end 1.733296 -1.549908)
			(stroke
				(width 0.1524)
				(type default)
			)
			(layer "F.SilkS")
		)
		(fp_line
			(start 1.733296 -1.549908)
			(end 0.660908 -1.549908)
			(stroke
				(width 0.1524)
				(type default)
			)
			(layer "F.SilkS")
		)
		(fp_line
			(start 0.660908 -1.549908)
			(end 0 -0.889)
			(stroke
				(width 0.1524)
				(type default)
			)
			(layer "F.SilkS")
		)
		(fp_line
			(start 0 -0.889)
			(end -0.660908 -1.549908)
			(stroke
				(width 0.1524)
				(type default)
			)
			(layer "F.SilkS")
		)
		(fp_line
			(start -0.660908 -1.549908)
			(end -1.733296 -1.549908)
			(stroke
				(width 0.1524)
				(type default)
			)
			(layer "F.SilkS")
		)
		(fp_line
			(start -1.733296 1.549908)
			(end 1.733296 1.549908)
			(stroke
				(width 0.1524)
				(type default)
			)
			(layer "F.SilkS")
		)
		(fp_line
			(start -1.733296 -1.549908)
			(end -1.733296 1.549908)
			(stroke
				(width 0.1524)
				(type default)
			)
			(layer "F.SilkS")
		)
		(fp_poly
			(pts
				(xy -0.982218 -2.318766) (xy -1.236218 -1.810766) (xy -1.490218 -2.318766)
			)
			(stroke
				(width 0)
				(type default)
			)
			(fill yes)
			(layer "F.SilkS")
		)
		(fp_line
			(start 0.849884 1.549908)
			(end 0.849884 -1.549908)
			(stroke
				(width 0.1)
				(type default)
			)
			(layer "F.Fab")
		)
		(fp_line
			(start 0.849884 -1.549908)
			(end -0.849884 -1.549908)
			(stroke
				(width 0.1)
				(type default)
			)
			(layer "F.Fab")
		)
		(fp_line
			(start -0.849884 1.549908)
			(end 0.849884 1.549908)
			(stroke
				(width 0.1)
				(type default)
			)
			(layer "F.Fab")
		)
		(fp_line
			(start -0.849884 -1.549908)
			(end -0.849884 1.549908)
			(stroke
				(width 0.1)
				(type default)
			)
			(layer "F.Fab")
		)
		(fp_poly
			(pts
				(xy -2.4384 -1.20396) (xy -2.4384 -0.69596) (xy -1.9304 -0.94996)
			)
			(stroke
				(width 0)
				(type default)
			)
			(fill yes)
			(layer "F.Fab")
		)
		(pad "1" smd rect
			(at -1.199896 -0.94996 90)
			(size 0.5588 0.8128)
			(layers "F.Cu" "F.Mask" "F.Paste")
			(net "NC_U157_NC1")
		)
		(pad "2" smd rect
			(at -1.199896 0 90)
			(size 0.5588 0.8128)
			(layers "F.Cu" "F.Mask" "F.Paste")
			(net "OCP_SFF_WAKE_BUFF_R_N")
		)
		(pad "3" smd rect
			(at -1.199896 0.94996 90)
			(size 0.5588 0.8128)
			(layers "F.Cu" "F.Mask" "F.Paste")
			(net "GND")
		)
		(pad "4" smd rect
			(at 1.199896 0.94996 90)
			(size 0.5588 0.8128)
			(layers "F.Cu" "F.Mask" "F.Paste")
			(net "IRQ_LVC3_WAKE_BUF_N")
		)
		(pad "5" smd rect
			(at 1.199896 -0.94996 90)
			(size 0.5588 0.8128)
			(layers "F.Cu" "F.Mask" "F.Paste")
			(net "P3V3_AUX")
		)
	)
	(footprint ""
		(layer "F.Cu")
		(at 136.60628 -26.251408)
		(property "Reference" "R4276"
			(at 0 0 0)
			(layer "F.SilkS")
			(hide yes)
			(effects
				(font
					(size 1.27 1.27)
				)
			)
		)
		(property "Value" ""
			(at 0 0 0)
			(layer "F.Fab")
			(effects
				(font
					(size 1.27 1.27)
				)
			)
		)
		(duplicate_pad_numbers_are_jumpers no)
		(fp_line
			(start -0.7874 -0.4064)
			(end 0.7874 -0.4064)
			(stroke
				(width 0.1524)
				(type default)
			)
			(layer "F.SilkS")
		)
		(fp_line
			(start -0.7874 0.4064)
			(end -0.7874 -0.4064)
			(stroke
				(width 0.1524)
				(type default)
			)
			(layer "F.SilkS")
		)
		(fp_line
			(start 0.7874 -0.4064)
			(end 0.7874 0.4064)
			(stroke
				(width 0.1524)
				(type default)
			)
			(layer "F.SilkS")
		)
		(fp_line
			(start 0.7874 0.4064)
			(end -0.7874 0.4064)
			(stroke
				(width 0.1524)
				(type default)
			)
			(layer "F.SilkS")
		)
		(fp_line
			(start -0.67945 -0.305054)
			(end -0.12065 -0.305054)
			(stroke
				(width 0.1)
				(type default)
			)
			(layer "F.Fab")
		)
		(fp_line
			(start -0.67945 0.3048)
			(end -0.67945 -0.305054)
			(stroke
				(width 0.1)
				(type default)
			)
			(layer "F.Fab")
		)
		(fp_line
			(start -0.12065 -0.305054)
			(end -0.12065 -0.2794)
			(stroke
				(width 0.1)
				(type default)
			)
			(layer "F.Fab")
		)
		(fp_line
			(start -0.12065 -0.2794)
			(end 0.12065 -0.2794)
			(stroke
				(width 0.1)
				(type default)
			)
			(layer "F.Fab")
		)
		(fp_line
			(start -0.12065 0.2794)
			(end -0.12065 0.3048)
			(stroke
				(width 0.1)
				(type default)
			)
			(layer "F.Fab")
		)
		(fp_line
			(start -0.12065 0.3048)
			(end -0.67945 0.3048)
			(stroke
				(width 0.1)
				(type default)
			)
			(layer "F.Fab")
		)
		(fp_line
			(start 0.120396 0.2794)
			(end -0.12065 0.2794)
			(stroke
				(width 0.1)
				(type default)
			)
			(layer "F.Fab")
		)
		(fp_line
			(start 0.120396 0.3048)
			(end 0.120396 0.2794)
			(stroke
				(width 0.1)
				(type default)
			)
			(layer "F.Fab")
		)
		(fp_line
			(start 0.12065 -0.3048)
			(end 0.67945 -0.3048)
			(stroke
				(width 0.1)
				(type default)
			)
			(layer "F.Fab")
		)
		(fp_line
			(start 0.12065 -0.2794)
			(end 0.12065 -0.3048)
			(stroke
				(width 0.1)
				(type default)
			)
			(layer "F.Fab")
		)
		(fp_line
			(start 0.67945 -0.3048)
			(end 0.67945 0.3048)
			(stroke
				(width 0.1)
				(type default)
			)
			(layer "F.Fab")
		)
		(fp_line
			(start 0.67945 0.3048)
			(end 0.120396 0.3048)
			(stroke
				(width 0.1)
				(type default)
			)
			(layer "F.Fab")
		)
		(pad "1" smd circle
			(at -0.40005 0)
			(size 0 0)
			(layers "F.Cu" "F.Mask" "F.Paste")
			(net "FM_USB3_1_EQA")
		)
		(pad "2" smd circle
			(at 0.40005 0)
			(size 0 0)
			(layers "F.Cu" "F.Mask" "F.Paste")
			(net "GND")
		)
	)
	(footprint ""
		(layer "F.Cu")
		(at 280.840688 -15.247112 180)
		(property "Reference" "R3192"
			(at 0 0 180)
			(layer "F.SilkS")
			(hide yes)
			(effects
				(font
					(size 1.27 1.27)
				)
			)
		)
		(property "Value" ""
			(at 0 0 180)
			(layer "F.Fab")
			(effects
				(font
					(size 1.27 1.27)
				)
			)
		)
		(duplicate_pad_numbers_are_jumpers no)
		(fp_line
			(start 0.7874 0.4064)
			(end -0.7874 0.4064)
			(stroke
				(width 0.1524)
				(type default)
			)
			(layer "F.SilkS")
		)
		(fp_line
			(start 0.7874 -0.4064)
			(end 0.7874 0.4064)
			(stroke
				(width 0.1524)
				(type default)
			)
			(layer "F.SilkS")
		)
		(fp_line
			(start -0.7874 0.4064)
			(end -0.7874 -0.4064)
			(stroke
				(width 0.1524)
				(type default)
			)
			(layer "F.SilkS")
		)
		(fp_line
			(start -0.7874 -0.4064)
			(end 0.7874 -0.4064)
			(stroke
				(width 0.1524)
				(type default)
			)
			(layer "F.SilkS")
		)
		(fp_line
			(start 0.67945 0.3048)
			(end 0.120396 0.3048)
			(stroke
				(width 0.1)
				(type default)
			)
			(layer "F.Fab")
		)
		(fp_line
			(start 0.67945 -0.3048)
			(end 0.67945 0.3048)
			(stroke
				(width 0.1)
				(type default)
			)
			(layer "F.Fab")
		)
		(fp_line
			(start 0.12065 -0.2794)
			(end 0.12065 -0.3048)
			(stroke
				(width 0.1)
				(type default)
			)
			(layer "F.Fab")
		)
		(fp_line
			(start 0.12065 -0.3048)
			(end 0.67945 -0.3048)
			(stroke
				(width 0.1)
				(type default)
			)
			(layer "F.Fab")
		)
		(fp_line
			(start 0.120396 0.3048)
			(end 0.120396 0.2794)
			(stroke
				(width 0.1)
				(type default)
			)
			(layer "F.Fab")
		)
		(fp_line
			(start 0.120396 0.2794)
			(end -0.12065 0.2794)
			(stroke
				(width 0.1)
				(type default)
			)
			(layer "F.Fab")
		)
		(fp_line
			(start -0.12065 0.3048)
			(end -0.67945 0.3048)
			(stroke
				(width 0.1)
				(type default)
			)
			(layer "F.Fab")
		)
		(fp_line
			(start -0.12065 0.2794)
			(end -0.12065 0.3048)
			(stroke
				(width 0.1)
				(type default)
			)
			(layer "F.Fab")
		)
		(fp_line
			(start -0.12065 -0.2794)
			(end 0.12065 -0.2794)
			(stroke
				(width 0.1)
				(type default)
			)
			(layer "F.Fab")
		)
		(fp_line
			(start -0.12065 -0.305054)
			(end -0.12065 -0.2794)
			(stroke
				(width 0.1)
				(type default)
			)
			(layer "F.Fab")
		)
		(fp_line
			(start -0.67945 0.3048)
			(end -0.67945 -0.305054)
			(stroke
				(width 0.1)
				(type default)
			)
			(layer "F.Fab")
		)
		(fp_line
			(start -0.67945 -0.305054)
			(end -0.12065 -0.305054)
			(stroke
				(width 0.1)
				(type default)
			)
			(layer "F.Fab")
		)
		(pad "1" smd circle
			(at -0.40005 0 180)
			(size 0 0)
			(layers "F.Cu" "F.Mask" "F.Paste")
			(net "P3V3_AUX")
		)
		(pad "2" smd circle
			(at 0.40005 0 180)
			(size 0 0)
			(layers "F.Cu" "F.Mask" "F.Paste")
			(net "IRQ_LVC3_V3_2_WAKE_BUF_N")
		)
	)
	(footprint ""
		(layer "F.Cu")
		(at 339.298534 -4.696206)
		(property "Reference" "J69"
			(at -4.245864 1.140206 90)
			(unlocked yes)
			(layer "F.SilkS")
			(effects
				(font
					(size 0.7874 0.5842)
					(thickness 0.1524)
				)
				(justify left)
			)
		)
		(property "Value" ""
			(at 0 0 0)
			(layer "F.Fab")
			(effects
				(font
					(size 1.27 1.27)
				)
			)
		)
		(duplicate_pad_numbers_are_jumpers no)
		(fp_line
			(start -1.2192 -2.1082)
			(end 1.2192 -2.1082)
			(stroke
				(width 0.1524)
				(type default)
			)
			(layer "F.SilkS")
		)
		(fp_line
			(start -1.2192 2.1082)
			(end -1.2192 -2.1082)
			(stroke
				(width 0.1524)
				(type default)
			)
			(layer "F.SilkS")
		)
		(fp_line
			(start 1.2192 -2.1082)
			(end 1.2192 2.1082)
			(stroke
				(width 0.1524)
				(type default)
			)
			(layer "F.SilkS")
		)
		(fp_line
			(start 1.2192 2.1082)
			(end -1.2192 2.1082)
			(stroke
				(width 0.1524)
				(type default)
			)
			(layer "F.SilkS")
		)
		(pad "" np_thru_hole circle
			(at -2.8829 -1.27 270)
			(size 1.0414 1.0414)
			(drill 1.0414)
			(layers "*.Cu" "*.Mask")
			(clearance 0.381)
			(thermal_gap 0.381)
		)
		(pad "" np_thru_hole circle
			(at -2.8829 1.27 270)
			(size 1.0414 1.0414)
			(drill 1.0414)
			(layers "*.Cu" "*.Mask")
			(clearance 0.381)
			(thermal_gap 0.381)
		)
		(pad "" np_thru_hole circle
			(at 3.4671 -1.27 270)
			(size 1.0414 1.0414)
			(drill 1.0414)
			(layers "*.Cu" "*.Mask")
			(clearance 0.381)
			(thermal_gap 0.381)
		)
		(pad "" np_thru_hole circle
			(at 3.4671 1.27 270)
			(size 1.0414 1.0414)
			(drill 1.0414)
			(layers "*.Cu" "*.Mask")
			(clearance 0.381)
			(thermal_gap 0.381)
		)
		(pad "1" smd rect
			(at 0.8255 -0.249936 270)
			(size 0.3048 0.508)
			(layers "F.Cu" "F.Mask" "F.Paste")
			(net "DELTA_L_85_5INCH_TOP_DN")
		)
		(pad "2" smd rect
			(at 0.8255 0.249936 270)
			(size 0.3048 0.508)
			(layers "F.Cu" "F.Mask" "F.Paste")
			(net "DELTA_L_85_5INCH_TOP_DP")
		)
		(pad "3" smd circle
			(at 0 0)
			(size 0 0)
			(layers "F.Cu" "F.Mask" "F.Paste")
			(net "DELTA_L_GND_1")
		)
		(zone
			(layer "F.Cu")
			(hatch none 0.5)
			(connect_pads
				(clearance 0)
			)
			(min_thickness 0.25)
			(keepout
				(tracks not_allowed)
				(vias allowed)
				(pads allowed)
				(copperpour not_allowed)
				(footprints allowed)
			)
			(placement
				(enabled no)
				(sheetname "")
			)
			(fill
				(thermal_gap 0.5)
				(thermal_bridge_width 0.5)
				(island_removal_mode 0)
			)
			(polygon
				(pts
					(xy 340.416134 -5.244846) (xy 340.416134 -5.149342) (xy 339.819234 -5.149342) (xy 339.819234 -4.742942)
					(xy 340.416134 -4.742942) (xy 340.416134 -4.64947) (xy 339.819234 -4.64947) (xy 339.819234 -4.24307)
					(xy 340.416134 -4.24307) (xy 340.416134 -4.147566) (xy 339.717634 -4.147566) (xy 339.717634 -5.244846)
				)
			)
		)
		(zone
			(layers "F.Cu" "B.Cu" "In1.Cu" "In2.Cu" "In3.Cu" "In4.Cu" "In5.Cu" "In6.Cu"
				"In7.Cu" "In8.Cu" "In9.Cu" "In10.Cu" "In11.Cu" "In12.Cu" "In13.Cu" "In14.Cu"
				"In15.Cu" "In16.Cu"
			)
			(hatch none 0.5)
			(connect_pads
				(clearance 0)
			)
			(min_thickness 0.25)
			(keepout
				(tracks not_allowed)
				(vias allowed)
				(pads allowed)
				(copperpour not_allowed)
				(footprints allowed)
			)
			(placement
				(enabled no)
				(sheetname "")
			)
			(fill
				(thermal_gap 0.5)
				(thermal_bridge_width 0.5)
				(island_removal_mode 0)
			)
			(polygon
				(pts
					(arc
						(start 337.342734 -5.966206)
						(mid 335.488534 -5.966206)
						(end 337.342734 -5.966206)
					)
				)
			)
		)
		(zone
			(layers "F.Cu" "B.Cu" "In1.Cu" "In2.Cu" "In3.Cu" "In4.Cu" "In5.Cu" "In6.Cu"
				"In7.Cu" "In8.Cu" "In9.Cu" "In10.Cu" "In11.Cu" "In12.Cu" "In13.Cu" "In14.Cu"
				"In15.Cu" "In16.Cu"
			)
			(hatch none 0.5)
			(connect_pads
				(clearance 0)
			)
			(min_thickness 0.25)
			(keepout
				(tracks not_allowed)
				(vias allowed)
				(pads allowed)
				(copperpour not_allowed)
				(footprints allowed)
			)
			(placement
				(enabled no)
				(sheetname "")
			)
			(fill
				(thermal_gap 0.5)
				(thermal_bridge_width 0.5)
				(island_removal_mode 0)
			)
			(polygon
				(pts
					(arc
						(start 337.342734 -3.426206)
						(mid 335.488534 -3.426206)
						(end 337.342734 -3.426206)
					)
				)
			)
		)
		(zone
			(layers "F.Cu" "B.Cu" "In1.Cu" "In2.Cu" "In3.Cu" "In4.Cu" "In5.Cu" "In6.Cu"
				"In7.Cu" "In8.Cu" "In9.Cu" "In10.Cu" "In11.Cu" "In12.Cu" "In13.Cu" "In14.Cu"
				"In15.Cu" "In16.Cu"
			)
			(hatch none 0.5)
			(connect_pads
				(clearance 0)
			)
			(min_thickness 0.25)
			(keepout
				(tracks not_allowed)
				(vias allowed)
				(pads allowed)
				(copperpour not_allowed)
				(footprints allowed)
			)
			(placement
				(enabled no)
				(sheetname "")
			)
			(fill
				(thermal_gap 0.5)
				(thermal_bridge_width 0.5)
				(island_removal_mode 0)
			)
			(polygon
				(pts
					(arc
						(start 343.692734 -5.966206)
						(mid 341.838534 -5.966206)
						(end 343.692734 -5.966206)
					)
				)
			)
		)
		(zone
			(layers "F.Cu" "B.Cu" "In1.Cu" "In2.Cu" "In3.Cu" "In4.Cu" "In5.Cu" "In6.Cu"
				"In7.Cu" "In8.Cu" "In9.Cu" "In10.Cu" "In11.Cu" "In12.Cu" "In13.Cu" "In14.Cu"
				"In15.Cu" "In16.Cu"
			)
			(hatch none 0.5)
			(connect_pads
				(clearance 0)
			)
			(min_thickness 0.25)
			(keepout
				(tracks not_allowed)
				(vias allowed)
				(pads allowed)
				(copperpour not_allowed)
				(footprints allowed)
			)
			(placement
				(enabled no)
				(sheetname "")
			)
			(fill
				(thermal_gap 0.5)
				(thermal_bridge_width 0.5)
				(island_removal_mode 0)
			)
			(polygon
				(pts
					(arc
						(start 343.692734 -3.426206)
						(mid 341.838534 -3.426206)
						(end 343.692734 -3.426206)
					)
				)
			)
		)
	)
)
